(kicad_pcb
	(version 20260206)
	(generator "pcbnew")
	(generator_version "10.0")
	(general
		(thickness 1.6)
		(legacy_teardrops no)
	)
	(paper "A4")
	(title_block
		(title "v1-pdb — T6M_PDB_D_0927_0900.brd")
		(comment 1 "Open CloudServer (Microsoft) / footprints 103-113 of 321")
	)
	(layers
		(0 "F.Cu" signal "TOP")
		(4 "In1.Cu" signal "GND")
		(6 "In2.Cu" signal "IN1")
		(8 "In3.Cu" signal "VCC")
		(10 "In4.Cu" signal "VCC1")
		(12 "In5.Cu" signal "IN2")
		(14 "In6.Cu" signal "GND1")
		(2 "B.Cu" signal "BOTTOM")
		(9 "F.Adhes" user "F.Adhesive")
		(11 "B.Adhes" user "B.Adhesive")
		(13 "F.Paste" user "Package Geometry/Pastemask Top")
		(15 "B.Paste" user "Package Geometry/Pastemask Bottom")
		(5 "F.SilkS" user "Ref Des/Silkscreen Top")
		(7 "B.SilkS" user "Ref Des/Silkscreen Bottom")
		(1 "F.Mask" user "Board Geometry/Soldermask Top")
		(3 "B.Mask" user "Board Geometry/Soldermask Bottom")
		(17 "Dwgs.User" user "User.Drawings")
		(19 "Cmts.User" user "User.Comments")
		(21 "Eco1.User" user "User.Eco1")
		(23 "Eco2.User" user "User.Eco2")
		(25 "Edge.Cuts" user "Board Geometry/Outline")
		(27 "Margin" user)
		(31 "F.CrtYd" user "Package Geometry/Place Bound Top")
		(29 "B.CrtYd" user "Package Geometry/Place Bound Bottom")
		(35 "F.Fab" user "Ref Des/Assembly Top")
		(33 "B.Fab" user "Ref Des/Assembly Bottom")
	)
	(footprint ""
		(layer "F.Cu")
		(at 45.911008 -261.777988 180)
		(property "Reference" "R104"
			(at 4.5974 0.054356 0)
			(unlocked yes)
			(layer "F.SilkS")
			(effects
				(font
					(size 0.7874 0.5842)
					(thickness 0.1524)
				)
				(justify left)
			)
		)
		(property "Value" ""
			(at 0 0 180)
			(layer "F.Fab")
			(effects
				(font
					(size 1.27 1.27)
				)
			)
		)
		(duplicate_pad_numbers_are_jumpers no)
		(fp_line
			(start 0.7874 0.4064)
			(end -0.7874 0.4064)
			(stroke
				(width 0.1524)
				(type default)
			)
			(layer "F.SilkS")
		)
		(fp_line
			(start 0.7874 -0.4064)
			(end 0.7874 0.4064)
			(stroke
				(width 0.1524)
				(type default)
			)
			(layer "F.SilkS")
		)
		(fp_line
			(start -0.7874 0.4064)
			(end -0.7874 -0.4064)
			(stroke
				(width 0.1524)
				(type default)
			)
			(layer "F.SilkS")
		)
		(fp_line
			(start -0.7874 -0.4064)
			(end 0.7874 -0.4064)
			(stroke
				(width 0.1524)
				(type default)
			)
			(layer "F.SilkS")
		)
		(fp_poly
			(pts
				(xy -0.508 0.2794) (xy -0.508 0.2286) (xy -0.635 0.2286) (xy -0.635 -0.254) (xy -0.5334 -0.254)
				(xy -0.5334 -0.2794) (xy 0.5334 -0.2794) (xy 0.5334 -0.254) (xy 0.635 -0.254) (xy 0.635 0.254) (xy 0.5334 0.254)
				(xy 0.5334 0.2794)
			)
			(stroke
				(width 0)
				(type default)
			)
			(fill no)
			(layer "F.CrtYd")
		)
		(pad "1" smd rect
			(at 0.40005 0 180)
			(size 0.4572 0.508)
			(layers "F.Cu" "F.Mask" "F.Paste")
			(net "PSU5_REMOTE_R_P")
		)
		(pad "2" smd rect
			(at -0.40005 0 180)
			(size 0.4572 0.508)
			(layers "F.Cu" "F.Mask" "F.Paste")
			(net "P12V")
		)
	)
	(footprint ""
		(layer "F.Cu")
		(at 72.403716 -397.262604 90)
		(property "Reference" "C70"
			(at -1.662176 -5.059172 90)
			(unlocked yes)
			(layer "F.SilkS")
			(effects
				(font
					(size 0.7874 0.5842)
					(thickness 0.1524)
				)
				(justify left)
			)
		)
		(property "Value" ""
			(at 0 0 90)
			(layer "F.Fab")
			(effects
				(font
					(size 1.27 1.27)
				)
			)
		)
		(duplicate_pad_numbers_are_jumpers no)
		(fp_line
			(start 0.7874 -0.4064)
			(end 0.7874 0.4064)
			(stroke
				(width 0.1524)
				(type default)
			)
			(layer "F.SilkS")
		)
		(fp_line
			(start -0.7874 -0.4064)
			(end 0.7874 -0.4064)
			(stroke
				(width 0.1524)
				(type default)
			)
			(layer "F.SilkS")
		)
		(fp_line
			(start 0 0.381)
			(end 0 -0.381)
			(stroke
				(width 0.1524)
				(type default)
			)
			(layer "F.SilkS")
		)
		(fp_line
			(start 0.7874 0.4064)
			(end -0.7874 0.4064)
			(stroke
				(width 0.1524)
				(type default)
			)
			(layer "F.SilkS")
		)
		(fp_line
			(start -0.7874 0.4064)
			(end -0.7874 -0.4064)
			(stroke
				(width 0.1524)
				(type default)
			)
			(layer "F.SilkS")
		)
		(fp_poly
			(pts
				(xy -0.5334 0.254) (xy -0.635 0.254) (xy -0.635 0.2286) (xy -0.635 -0.254) (xy -0.5334 -0.254) (xy -0.5334 -0.2794)
				(xy 0.5334 -0.2794) (xy 0.5334 -0.254) (xy 0.635 -0.254) (xy 0.635 0.254) (xy 0.5334 0.254) (xy 0.5334 0.2794)
				(xy -0.508 0.2794) (xy -0.5334 0.2794)
			)
			(stroke
				(width 0)
				(type default)
			)
			(fill no)
			(layer "F.CrtYd")
		)
		(pad "1" smd rect
			(at 0.40005 0 90)
			(size 0.4572 0.508)
			(layers "F.Cu" "F.Mask" "F.Paste")
			(net "P12V")
		)
		(pad "2" smd rect
			(at -0.40005 0 90)
			(size 0.4572 0.508)
			(layers "F.Cu" "F.Mask" "F.Paste")
			(net "GND")
		)
	)
	(footprint ""
		(layer "F.Cu")
		(at 13.463778 -324.01002 180)
		(property "Reference" "R146"
			(at -1.034796 0.001778 0)
			(unlocked yes)
			(layer "F.SilkS")
			(effects
				(font
					(size 0.7874 0.5842)
					(thickness 0.1524)
				)
				(justify left)
			)
		)
		(property "Value" ""
			(at 0 0 180)
			(layer "F.Fab")
			(effects
				(font
					(size 1.27 1.27)
				)
			)
		)
		(duplicate_pad_numbers_are_jumpers no)
		(fp_line
			(start 0.7874 0.4064)
			(end -0.7874 0.4064)
			(stroke
				(width 0.1524)
				(type default)
			)
			(layer "F.SilkS")
		)
		(fp_line
			(start 0.7874 -0.4064)
			(end 0.7874 0.4064)
			(stroke
				(width 0.1524)
				(type default)
			)
			(layer "F.SilkS")
		)
		(fp_line
			(start -0.7874 0.4064)
			(end -0.7874 -0.4064)
			(stroke
				(width 0.1524)
				(type default)
			)
			(layer "F.SilkS")
		)
		(fp_line
			(start -0.7874 -0.4064)
			(end 0.7874 -0.4064)
			(stroke
				(width 0.1524)
				(type default)
			)
			(layer "F.SilkS")
		)
		(fp_poly
			(pts
				(xy -0.508 0.2794) (xy -0.508 0.2286) (xy -0.635 0.2286) (xy -0.635 -0.254) (xy -0.5334 -0.254)
				(xy -0.5334 -0.2794) (xy 0.5334 -0.2794) (xy 0.5334 -0.254) (xy 0.635 -0.254) (xy 0.635 0.254) (xy 0.5334 0.254)
				(xy 0.5334 0.2794)
			)
			(stroke
				(width 0)
				(type default)
			)
			(fill no)
			(layer "F.CrtYd")
		)
		(pad "1" smd rect
			(at 0.40005 0 180)
			(size 0.4572 0.508)
			(layers "F.Cu" "F.Mask" "F.Paste")
			(net "FAN5_TACH")
		)
		(pad "2" smd rect
			(at -0.40005 0 180)
			(size 0.4572 0.508)
			(layers "F.Cu" "F.Mask" "F.Paste")
			(net "P12V")
		)
	)
	(footprint ""
		(layer "F.Cu")
		(at 74.709782 -326.522588 -90)
		(property "Reference" "C52"
			(at -2.752344 0.057404 90)
			(unlocked yes)
			(layer "F.SilkS")
			(effects
				(font
					(size 0.7874 0.5842)
					(thickness 0.1524)
				)
				(justify left)
			)
		)
		(property "Value" ""
			(at 0 0 270)
			(layer "F.Fab")
			(effects
				(font
					(size 1.27 1.27)
				)
			)
		)
		(duplicate_pad_numbers_are_jumpers no)
		(fp_line
			(start -0.7874 0.4064)
			(end -0.7874 -0.4064)
			(stroke
				(width 0.1524)
				(type default)
			)
			(layer "F.SilkS")
		)
		(fp_line
			(start 0.7874 0.4064)
			(end -0.7874 0.4064)
			(stroke
				(width 0.1524)
				(type default)
			)
			(layer "F.SilkS")
		)
		(fp_line
			(start 0 0.381)
			(end 0 -0.381)
			(stroke
				(width 0.1524)
				(type default)
			)
			(layer "F.SilkS")
		)
		(fp_line
			(start -0.7874 -0.4064)
			(end 0.7874 -0.4064)
			(stroke
				(width 0.1524)
				(type default)
			)
			(layer "F.SilkS")
		)
		(fp_line
			(start 0.7874 -0.4064)
			(end 0.7874 0.4064)
			(stroke
				(width 0.1524)
				(type default)
			)
			(layer "F.SilkS")
		)
		(fp_poly
			(pts
				(xy -0.5334 0.254) (xy -0.635 0.254) (xy -0.635 0.2286) (xy -0.635 -0.254) (xy -0.5334 -0.254) (xy -0.5334 -0.2794)
				(xy 0.5334 -0.2794) (xy 0.5334 -0.254) (xy 0.635 -0.254) (xy 0.635 0.254) (xy 0.5334 0.254) (xy 0.5334 0.2794)
				(xy -0.508 0.2794) (xy -0.5334 0.2794)
			)
			(stroke
				(width 0)
				(type default)
			)
			(fill no)
			(layer "F.CrtYd")
		)
		(pad "1" smd rect
			(at 0.40005 0 270)
			(size 0.4572 0.508)
			(layers "F.Cu" "F.Mask" "F.Paste")
			(net "P12V")
		)
		(pad "2" smd rect
			(at -0.40005 0 270)
			(size 0.4572 0.508)
			(layers "F.Cu" "F.Mask" "F.Paste")
			(net "GND")
		)
	)
	(footprint ""
		(layer "F.Cu")
		(at 40.959024 -105.82148 -90)
		(property "Reference" "R8"
			(at 0.823722 -2.429256 90)
			(unlocked yes)
			(layer "F.SilkS")
			(effects
				(font
					(size 0.7874 0.5842)
					(thickness 0.1524)
				)
				(justify left)
			)
		)
		(property "Value" ""
			(at 0 0 270)
			(layer "F.Fab")
			(effects
				(font
					(size 1.27 1.27)
				)
			)
		)
		(duplicate_pad_numbers_are_jumpers no)
		(fp_line
			(start -0.7874 0.4064)
			(end -0.7874 -0.4064)
			(stroke
				(width 0.1524)
				(type default)
			)
			(layer "F.SilkS")
		)
		(fp_line
			(start 0.7874 0.4064)
			(end -0.7874 0.4064)
			(stroke
				(width 0.1524)
				(type default)
			)
			(layer "F.SilkS")
		)
		(fp_line
			(start -0.7874 -0.4064)
			(end 0.7874 -0.4064)
			(stroke
				(width 0.1524)
				(type default)
			)
			(layer "F.SilkS")
		)
		(fp_line
			(start 0.7874 -0.4064)
			(end 0.7874 0.4064)
			(stroke
				(width 0.1524)
				(type default)
			)
			(layer "F.SilkS")
		)
		(fp_poly
			(pts
				(xy -0.508 0.2794) (xy -0.508 0.2286) (xy -0.635 0.2286) (xy -0.635 -0.254) (xy -0.5334 -0.254)
				(xy -0.5334 -0.2794) (xy 0.5334 -0.2794) (xy 0.5334 -0.254) (xy 0.635 -0.254) (xy 0.635 0.254) (xy 0.5334 0.254)
				(xy 0.5334 0.2794)
			)
			(stroke
				(width 0)
				(type default)
			)
			(fill no)
			(layer "F.CrtYd")
		)
		(pad "1" smd rect
			(at 0.40005 0 270)
			(size 0.4572 0.508)
			(layers "F.Cu" "F.Mask" "F.Paste")
			(net "PSU2_AD0")
		)
		(pad "2" smd rect
			(at -0.40005 0 270)
			(size 0.4572 0.508)
			(layers "F.Cu" "F.Mask" "F.Paste")
			(net "GND")
		)
	)
	(footprint ""
		(layer "F.Cu")
		(at 39.705534 -105.822242 -90)
		(property "Reference" "R4"
			(at 0.830326 -2.570734 90)
			(unlocked yes)
			(layer "F.SilkS")
			(effects
				(font
					(size 0.7874 0.5842)
					(thickness 0.1524)
				)
				(justify left)
			)
		)
		(property "Value" ""
			(at 0 0 270)
			(layer "F.Fab")
			(effects
				(font
					(size 1.27 1.27)
				)
			)
		)
		(duplicate_pad_numbers_are_jumpers no)
		(fp_line
			(start -0.7874 0.4064)
			(end -0.7874 -0.4064)
			(stroke
				(width 0.1524)
				(type default)
			)
			(layer "F.SilkS")
		)
		(fp_line
			(start 0.7874 0.4064)
			(end -0.7874 0.4064)
			(stroke
				(width 0.1524)
				(type default)
			)
			(layer "F.SilkS")
		)
		(fp_line
			(start -0.7874 -0.4064)
			(end 0.7874 -0.4064)
			(stroke
				(width 0.1524)
				(type default)
			)
			(layer "F.SilkS")
		)
		(fp_line
			(start 0.7874 -0.4064)
			(end 0.7874 0.4064)
			(stroke
				(width 0.1524)
				(type default)
			)
			(layer "F.SilkS")
		)
		(fp_poly
			(pts
				(xy -0.508 0.2794) (xy -0.508 0.2286) (xy -0.635 0.2286) (xy -0.635 -0.254) (xy -0.5334 -0.254)
				(xy -0.5334 -0.2794) (xy 0.5334 -0.2794) (xy 0.5334 -0.254) (xy 0.635 -0.254) (xy 0.635 0.254) (xy 0.5334 0.254)
				(xy 0.5334 0.2794)
			)
			(stroke
				(width 0)
				(type default)
			)
			(fill no)
			(layer "F.CrtYd")
		)
		(pad "1" smd rect
			(at 0.40005 0 270)
			(size 0.4572 0.508)
			(layers "F.Cu" "F.Mask" "F.Paste")
			(net "PSU2_AD0")
		)
		(pad "2" smd rect
			(at -0.40005 0 270)
			(size 0.4572 0.508)
			(layers "F.Cu" "F.Mask" "F.Paste")
			(net "P12V_STBY")
		)
	)
	(footprint ""
		(layer "F.Cu")
		(at 26.102056 -272.345404)
		(property "Reference" "R57"
			(at -4.037838 -0.005334 0)
			(unlocked yes)
			(layer "F.SilkS")
			(effects
				(font
					(size 0.7874 0.5842)
					(thickness 0.1524)
				)
				(justify left)
			)
		)
		(property "Value" ""
			(at 0 0 0)
			(layer "F.Fab")
			(effects
				(font
					(size 1.27 1.27)
				)
			)
		)
		(duplicate_pad_numbers_are_jumpers no)
		(fp_line
			(start -0.7874 -0.4064)
			(end 0.7874 -0.4064)
			(stroke
				(width 0.1524)
				(type default)
			)
			(layer "F.SilkS")
		)
		(fp_line
			(start -0.7874 0.4064)
			(end -0.7874 -0.4064)
			(stroke
				(width 0.1524)
				(type default)
			)
			(layer "F.SilkS")
		)
		(fp_line
			(start 0.7874 -0.4064)
			(end 0.7874 0.4064)
			(stroke
				(width 0.1524)
				(type default)
			)
			(layer "F.SilkS")
		)
		(fp_line
			(start 0.7874 0.4064)
			(end -0.7874 0.4064)
			(stroke
				(width 0.1524)
				(type default)
			)
			(layer "F.SilkS")
		)
		(fp_poly
			(pts
				(xy -0.508 0.2794) (xy -0.508 0.2286) (xy -0.635 0.2286) (xy -0.635 -0.254) (xy -0.5334 -0.254)
				(xy -0.5334 -0.2794) (xy 0.5334 -0.2794) (xy 0.5334 -0.254) (xy 0.635 -0.254) (xy 0.635 0.254) (xy 0.5334 0.254)
				(xy 0.5334 0.2794)
			)
			(stroke
				(width 0)
				(type default)
			)
			(fill no)
			(layer "F.CrtYd")
		)
		(pad "1" smd rect
			(at 0.40005 0)
			(size 0.4572 0.508)
			(layers "F.Cu" "F.Mask" "F.Paste")
			(net "PSU4_RESET")
		)
		(pad "2" smd rect
			(at -0.40005 0)
			(size 0.4572 0.508)
			(layers "F.Cu" "F.Mask" "F.Paste")
			(net "GND")
		)
	)
	(footprint ""
		(layer "F.Cu")
		(at 39.858188 -287.573212 180)
		(property "Reference" "R15"
			(at -1.140714 0.062738 0)
			(unlocked yes)
			(layer "F.SilkS")
			(effects
				(font
					(size 0.7874 0.5842)
					(thickness 0.1524)
				)
				(justify left)
			)
		)
		(property "Value" ""
			(at 0 0 180)
			(layer "F.Fab")
			(effects
				(font
					(size 1.27 1.27)
				)
			)
		)
		(duplicate_pad_numbers_are_jumpers no)
		(fp_line
			(start 0.7874 0.4064)
			(end -0.7874 0.4064)
			(stroke
				(width 0.1524)
				(type default)
			)
			(layer "F.SilkS")
		)
		(fp_line
			(start 0.7874 -0.4064)
			(end 0.7874 0.4064)
			(stroke
				(width 0.1524)
				(type default)
			)
			(layer "F.SilkS")
		)
		(fp_line
			(start -0.7874 0.4064)
			(end -0.7874 -0.4064)
			(stroke
				(width 0.1524)
				(type default)
			)
			(layer "F.SilkS")
		)
		(fp_line
			(start -0.7874 -0.4064)
			(end 0.7874 -0.4064)
			(stroke
				(width 0.1524)
				(type default)
			)
			(layer "F.SilkS")
		)
		(fp_poly
			(pts
				(xy -0.508 0.2794) (xy -0.508 0.2286) (xy -0.635 0.2286) (xy -0.635 -0.254) (xy -0.5334 -0.254)
				(xy -0.5334 -0.2794) (xy 0.5334 -0.2794) (xy 0.5334 -0.254) (xy 0.635 -0.254) (xy 0.635 0.254) (xy 0.5334 0.254)
				(xy 0.5334 0.2794)
			)
			(stroke
				(width 0)
				(type default)
			)
			(fill no)
			(layer "F.CrtYd")
		)
		(pad "1" smd rect
			(at 0.40005 0 180)
			(size 0.4572 0.508)
			(layers "F.Cu" "F.Mask" "F.Paste")
			(net "PSU4_REMOTE_P")
		)
		(pad "2" smd rect
			(at -0.40005 0 180)
			(size 0.4572 0.508)
			(layers "F.Cu" "F.Mask" "F.Paste")
			(net "P12V")
		)
	)
	(footprint ""
		(layer "F.Cu")
		(at 12.784074 -330.48067 -90)
		(property "Reference" "R34"
			(at 3.685032 -0.234188 90)
			(unlocked yes)
			(layer "F.SilkS")
			(effects
				(font
					(size 0.7874 0.5842)
					(thickness 0.1524)
				)
				(justify left)
			)
		)
		(property "Value" ""
			(at 0 0 270)
			(layer "F.Fab")
			(effects
				(font
					(size 1.27 1.27)
				)
			)
		)
		(duplicate_pad_numbers_are_jumpers no)
		(fp_line
			(start -0.7874 0.4064)
			(end -0.7874 -0.4064)
			(stroke
				(width 0.1524)
				(type default)
			)
			(layer "F.SilkS")
		)
		(fp_line
			(start 0.7874 0.4064)
			(end -0.7874 0.4064)
			(stroke
				(width 0.1524)
				(type default)
			)
			(layer "F.SilkS")
		)
		(fp_line
			(start -0.7874 -0.4064)
			(end 0.7874 -0.4064)
			(stroke
				(width 0.1524)
				(type default)
			)
			(layer "F.SilkS")
		)
		(fp_line
			(start 0.7874 -0.4064)
			(end 0.7874 0.4064)
			(stroke
				(width 0.1524)
				(type default)
			)
			(layer "F.SilkS")
		)
		(fp_poly
			(pts
				(xy -0.508 0.2794) (xy -0.508 0.2286) (xy -0.635 0.2286) (xy -0.635 -0.254) (xy -0.5334 -0.254)
				(xy -0.5334 -0.2794) (xy 0.5334 -0.2794) (xy 0.5334 -0.254) (xy 0.635 -0.254) (xy 0.635 0.254) (xy 0.5334 0.254)
				(xy 0.5334 0.2794)
			)
			(stroke
				(width 0)
				(type default)
			)
			(fill no)
			(layer "F.CrtYd")
		)
		(pad "1" smd rect
			(at 0.40005 0 270)
			(size 0.4572 0.508)
			(layers "F.Cu" "F.Mask" "F.Paste")
			(net "P3V3")
		)
		(pad "2" smd rect
			(at -0.40005 0 270)
			(size 0.4572 0.508)
			(layers "F.Cu" "F.Mask" "F.Paste")
			(net "FRU_A0")
		)
	)
	(footprint ""
		(layer "F.Cu")
		(at 72.19696 -354.308918 90)
		(property "Reference" "C60"
			(at -3.926332 0.77978 90)
			(unlocked yes)
			(layer "F.SilkS")
			(effects
				(font
					(size 0.7874 0.5842)
					(thickness 0.1524)
				)
				(justify left)
			)
		)
		(property "Value" ""
			(at 0 0 90)
			(layer "F.Fab")
			(effects
				(font
					(size 1.27 1.27)
				)
			)
		)
		(duplicate_pad_numbers_are_jumpers no)
		(fp_line
			(start 0.7874 -0.4064)
			(end 0.7874 0.4064)
			(stroke
				(width 0.1524)
				(type default)
			)
			(layer "F.SilkS")
		)
		(fp_line
			(start -0.7874 -0.4064)
			(end 0.7874 -0.4064)
			(stroke
				(width 0.1524)
				(type default)
			)
			(layer "F.SilkS")
		)
		(fp_line
			(start 0 0.381)
			(end 0 -0.381)
			(stroke
				(width 0.1524)
				(type default)
			)
			(layer "F.SilkS")
		)
		(fp_line
			(start 0.7874 0.4064)
			(end -0.7874 0.4064)
			(stroke
				(width 0.1524)
				(type default)
			)
			(layer "F.SilkS")
		)
		(fp_line
			(start -0.7874 0.4064)
			(end -0.7874 -0.4064)
			(stroke
				(width 0.1524)
				(type default)
			)
			(layer "F.SilkS")
		)
		(fp_poly
			(pts
				(xy -0.5334 0.254) (xy -0.635 0.254) (xy -0.635 0.2286) (xy -0.635 -0.254) (xy -0.5334 -0.254) (xy -0.5334 -0.2794)
				(xy 0.5334 -0.2794) (xy 0.5334 -0.254) (xy 0.635 -0.254) (xy 0.635 0.254) (xy 0.5334 0.254) (xy 0.5334 0.2794)
				(xy -0.508 0.2794) (xy -0.5334 0.2794)
			)
			(stroke
				(width 0)
				(type default)
			)
			(fill no)
			(layer "F.CrtYd")
		)
		(pad "1" smd rect
			(at 0.40005 0 90)
			(size 0.4572 0.508)
			(layers "F.Cu" "F.Mask" "F.Paste")
			(net "P12V")
		)
		(pad "2" smd rect
			(at -0.40005 0 90)
			(size 0.4572 0.508)
			(layers "F.Cu" "F.Mask" "F.Paste")
			(net "GND")
		)
	)
	(footprint ""
		(layer "F.Cu")
		(at 13.853922 -330.480924 -90)
		(property "Reference" "R37"
			(at 3.685032 -0.234188 90)
			(unlocked yes)
			(layer "F.SilkS")
			(effects
				(font
					(size 0.7874 0.5842)
					(thickness 0.1524)
				)
				(justify left)
			)
		)
		(property "Value" ""
			(at 0 0 270)
			(layer "F.Fab")
			(effects
				(font
					(size 1.27 1.27)
				)
			)
		)
		(duplicate_pad_numbers_are_jumpers no)
		(fp_line
			(start -0.7874 0.4064)
			(end -0.7874 -0.4064)
			(stroke
				(width 0.1524)
				(type default)
			)
			(layer "F.SilkS")
		)
		(fp_line
			(start 0.7874 0.4064)
			(end -0.7874 0.4064)
			(stroke
				(width 0.1524)
				(type default)
			)
			(layer "F.SilkS")
		)
		(fp_line
			(start -0.7874 -0.4064)
			(end 0.7874 -0.4064)
			(stroke
				(width 0.1524)
				(type default)
			)
			(layer "F.SilkS")
		)
		(fp_line
			(start 0.7874 -0.4064)
			(end 0.7874 0.4064)
			(stroke
				(width 0.1524)
				(type default)
			)
			(layer "F.SilkS")
		)
		(fp_poly
			(pts
				(xy -0.508 0.2794) (xy -0.508 0.2286) (xy -0.635 0.2286) (xy -0.635 -0.254) (xy -0.5334 -0.254)
				(xy -0.5334 -0.2794) (xy 0.5334 -0.2794) (xy 0.5334 -0.254) (xy 0.635 -0.254) (xy 0.635 0.254) (xy 0.5334 0.254)
				(xy 0.5334 0.2794)
			)
			(stroke
				(width 0)
				(type default)
			)
			(fill no)
			(layer "F.CrtYd")
		)
		(pad "1" smd rect
			(at 0.40005 0 270)
			(size 0.4572 0.508)
			(layers "F.Cu" "F.Mask" "F.Paste")
			(net "GND")
		)
		(pad "2" smd rect
			(at -0.40005 0 270)
			(size 0.4572 0.508)
			(layers "F.Cu" "F.Mask" "F.Paste")
			(net "FRU_A0")
		)
	)
)
